(kicad_pcb
	(version 20260206)
	(generator "pcbnew")
	(generator_version "10.0")
	(general
		(thickness 1.6)
		(legacy_teardrops no)
	)
	(paper "A4")
	(title_block
		(title "04192023_DAF0TMB3IC0_F0TG_MB_C_brd_V02_OCP.brd")
		(comment 1 "Grand Teton / footprints 2668-2674 of 8354")
	)
	(layers
		(0 "F.Cu" signal "TOP")
		(4 "In1.Cu" signal "GND")
		(6 "In2.Cu" signal "IN1")
		(8 "In3.Cu" signal "GND1")
		(10 "In4.Cu" signal "IN2")
		(12 "In5.Cu" signal "GND2")
		(14 "In6.Cu" signal "IN3")
		(16 "In7.Cu" signal "GND3")
		(18 "In8.Cu" signal "VCC")
		(20 "In9.Cu" signal "VCC1")
		(22 "In10.Cu" signal "GND4")
		(24 "In11.Cu" signal "IN4")
		(26 "In12.Cu" signal "GND5")
		(28 "In13.Cu" signal "IN5")
		(30 "In14.Cu" signal "GND6")
		(32 "In15.Cu" signal "IN6")
		(34 "In16.Cu" signal "GND7")
		(2 "B.Cu" signal "BOTTOM")
		(9 "F.Adhes" user "F.Adhesive")
		(11 "B.Adhes" user "B.Adhesive")
		(13 "F.Paste" user "Package Geometry/Pastemask Top")
		(15 "B.Paste" user "Package Geometry/Pastemask Bottom")
		(5 "F.SilkS" user "Ref Des/Silkscreen Top")
		(7 "B.SilkS" user "Ref Des/Silkscreen Bottom")
		(1 "F.Mask" user "Board Geometry/Soldermask Top")
		(3 "B.Mask" user "Board Geometry/Soldermask Bottom")
		(17 "Dwgs.User" user "User.Drawings")
		(19 "Cmts.User" user "User.Comments")
		(21 "Eco1.User" user "User.Eco1")
		(23 "Eco2.User" user "User.Eco2")
		(25 "Edge.Cuts" user "Board Geometry/Outline")
		(27 "Margin" user)
		(31 "F.CrtYd" user "Package Geometry/Place Bound Top")
		(29 "B.CrtYd" user "Package Geometry/Place Bound Bottom")
		(35 "F.Fab" user "Ref Des/Assembly Top")
		(33 "B.Fab" user "Ref Des/Assembly Bottom")
	)
	(footprint ""
		(layer "F.Cu")
		(at 178.830224 -147.086574 90)
		(property "Reference" "R499"
			(at 0 0 90)
			(layer "F.SilkS")
			(hide yes)
			(effects
				(font
					(size 1.27 1.27)
				)
			)
		)
		(property "Value" ""
			(at 0 0 90)
			(layer "F.Fab")
			(effects
				(font
					(size 1.27 1.27)
				)
			)
		)
		(duplicate_pad_numbers_are_jumpers no)
		(fp_line
			(start 0.7874 -0.4064)
			(end 0.7874 0.4064)
			(stroke
				(width 0.1524)
				(type default)
			)
			(layer "F.SilkS")
		)
		(fp_line
			(start -0.7874 -0.4064)
			(end 0.7874 -0.4064)
			(stroke
				(width 0.1524)
				(type default)
			)
			(layer "F.SilkS")
		)
		(fp_line
			(start 0.7874 0.4064)
			(end -0.7874 0.4064)
			(stroke
				(width 0.1524)
				(type default)
			)
			(layer "F.SilkS")
		)
		(fp_line
			(start -0.7874 0.4064)
			(end -0.7874 -0.4064)
			(stroke
				(width 0.1524)
				(type default)
			)
			(layer "F.SilkS")
		)
		(fp_line
			(start -0.12065 -0.305054)
			(end -0.12065 -0.2794)
			(stroke
				(width 0.1)
				(type default)
			)
			(layer "F.Fab")
		)
		(fp_line
			(start -0.67945 -0.305054)
			(end -0.12065 -0.305054)
			(stroke
				(width 0.1)
				(type default)
			)
			(layer "F.Fab")
		)
		(fp_line
			(start 0.67945 -0.3048)
			(end 0.67945 0.3048)
			(stroke
				(width 0.1)
				(type default)
			)
			(layer "F.Fab")
		)
		(fp_line
			(start 0.12065 -0.3048)
			(end 0.67945 -0.3048)
			(stroke
				(width 0.1)
				(type default)
			)
			(layer "F.Fab")
		)
		(fp_line
			(start 0.12065 -0.2794)
			(end 0.12065 -0.3048)
			(stroke
				(width 0.1)
				(type default)
			)
			(layer "F.Fab")
		)
		(fp_line
			(start -0.12065 -0.2794)
			(end 0.12065 -0.2794)
			(stroke
				(width 0.1)
				(type default)
			)
			(layer "F.Fab")
		)
		(fp_line
			(start 0.120396 0.2794)
			(end -0.12065 0.2794)
			(stroke
				(width 0.1)
				(type default)
			)
			(layer "F.Fab")
		)
		(fp_line
			(start -0.12065 0.2794)
			(end -0.12065 0.3048)
			(stroke
				(width 0.1)
				(type default)
			)
			(layer "F.Fab")
		)
		(fp_line
			(start 0.67945 0.3048)
			(end 0.120396 0.3048)
			(stroke
				(width 0.1)
				(type default)
			)
			(layer "F.Fab")
		)
		(fp_line
			(start 0.120396 0.3048)
			(end 0.120396 0.2794)
			(stroke
				(width 0.1)
				(type default)
			)
			(layer "F.Fab")
		)
		(fp_line
			(start -0.12065 0.3048)
			(end -0.67945 0.3048)
			(stroke
				(width 0.1)
				(type default)
			)
			(layer "F.Fab")
		)
		(fp_line
			(start -0.67945 0.3048)
			(end -0.67945 -0.305054)
			(stroke
				(width 0.1)
				(type default)
			)
			(layer "F.Fab")
		)
		(pad "1" smd circle
			(at -0.40005 0 90)
			(size 0 0)
			(layers "F.Cu" "F.Mask" "F.Paste")
			(net "P3V3_AUX")
		)
		(pad "2" smd circle
			(at 0.40005 0 90)
			(size 0 0)
			(layers "F.Cu" "F.Mask" "F.Paste")
			(net "SMB_CPU0_4_XLTR_SCL")
		)
	)
	(footprint ""
		(layer "F.Cu")
		(at 163.4236 -440.182)
		(property "Reference" "R2830"
			(at 0 0 0)
			(layer "F.SilkS")
			(hide yes)
			(effects
				(font
					(size 1.27 1.27)
				)
			)
		)
		(property "Value" ""
			(at 0 0 0)
			(layer "F.Fab")
			(effects
				(font
					(size 1.27 1.27)
				)
			)
		)
		(duplicate_pad_numbers_are_jumpers no)
		(fp_line
			(start -0.7874 -0.4064)
			(end 0.7874 -0.4064)
			(stroke
				(width 0.1524)
				(type default)
			)
			(layer "F.SilkS")
		)
		(fp_line
			(start -0.7874 0.4064)
			(end -0.7874 -0.4064)
			(stroke
				(width 0.1524)
				(type default)
			)
			(layer "F.SilkS")
		)
		(fp_line
			(start 0.7874 -0.4064)
			(end 0.7874 0.4064)
			(stroke
				(width 0.1524)
				(type default)
			)
			(layer "F.SilkS")
		)
		(fp_line
			(start 0.7874 0.4064)
			(end -0.7874 0.4064)
			(stroke
				(width 0.1524)
				(type default)
			)
			(layer "F.SilkS")
		)
		(fp_line
			(start -0.67945 -0.305054)
			(end -0.12065 -0.305054)
			(stroke
				(width 0.1)
				(type default)
			)
			(layer "F.Fab")
		)
		(fp_line
			(start -0.67945 0.3048)
			(end -0.67945 -0.305054)
			(stroke
				(width 0.1)
				(type default)
			)
			(layer "F.Fab")
		)
		(fp_line
			(start -0.12065 -0.305054)
			(end -0.12065 -0.2794)
			(stroke
				(width 0.1)
				(type default)
			)
			(layer "F.Fab")
		)
		(fp_line
			(start -0.12065 -0.2794)
			(end 0.12065 -0.2794)
			(stroke
				(width 0.1)
				(type default)
			)
			(layer "F.Fab")
		)
		(fp_line
			(start -0.12065 0.2794)
			(end -0.12065 0.3048)
			(stroke
				(width 0.1)
				(type default)
			)
			(layer "F.Fab")
		)
		(fp_line
			(start -0.12065 0.3048)
			(end -0.67945 0.3048)
			(stroke
				(width 0.1)
				(type default)
			)
			(layer "F.Fab")
		)
		(fp_line
			(start 0.120396 0.2794)
			(end -0.12065 0.2794)
			(stroke
				(width 0.1)
				(type default)
			)
			(layer "F.Fab")
		)
		(fp_line
			(start 0.120396 0.3048)
			(end 0.120396 0.2794)
			(stroke
				(width 0.1)
				(type default)
			)
			(layer "F.Fab")
		)
		(fp_line
			(start 0.12065 -0.3048)
			(end 0.67945 -0.3048)
			(stroke
				(width 0.1)
				(type default)
			)
			(layer "F.Fab")
		)
		(fp_line
			(start 0.12065 -0.2794)
			(end 0.12065 -0.3048)
			(stroke
				(width 0.1)
				(type default)
			)
			(layer "F.Fab")
		)
		(fp_line
			(start 0.67945 -0.3048)
			(end 0.67945 0.3048)
			(stroke
				(width 0.1)
				(type default)
			)
			(layer "F.Fab")
		)
		(fp_line
			(start 0.67945 0.3048)
			(end 0.120396 0.3048)
			(stroke
				(width 0.1)
				(type default)
			)
			(layer "F.Fab")
		)
		(pad "1" smd circle
			(at -0.40005 0)
			(size 0 0)
			(layers "F.Cu" "F.Mask" "F.Paste")
			(net "P3V3_AUX")
		)
		(pad "2" smd circle
			(at 0.40005 0)
			(size 0 0)
			(layers "F.Cu" "F.Mask" "F.Paste")
			(net "BIC_MONITER")
		)
	)
	(footprint ""
		(layer "F.Cu")
		(at 351.4852 -407.8732 90)
		(property "Reference" "R1470"
			(at 0 0 90)
			(layer "F.SilkS")
			(hide yes)
			(effects
				(font
					(size 1.27 1.27)
				)
			)
		)
		(property "Value" ""
			(at 0 0 90)
			(layer "F.Fab")
			(effects
				(font
					(size 1.27 1.27)
				)
			)
		)
		(duplicate_pad_numbers_are_jumpers no)
		(fp_line
			(start 0.32512 -0.175006)
			(end 0.32512 0.175006)
			(stroke
				(width 0.1)
				(type default)
			)
			(layer "F.Fab")
		)
		(fp_line
			(start -0.32512 -0.175006)
			(end 0.32512 -0.175006)
			(stroke
				(width 0.1)
				(type default)
			)
			(layer "F.Fab")
		)
		(fp_line
			(start 0.32512 0.175006)
			(end -0.32512 0.175006)
			(stroke
				(width 0.1)
				(type default)
			)
			(layer "F.Fab")
		)
		(fp_line
			(start -0.32512 0.175006)
			(end -0.32512 -0.175006)
			(stroke
				(width 0.1)
				(type default)
			)
			(layer "F.Fab")
		)
		(pad "1" smd rect
			(at -0.2667 0 90)
			(size 0.3048 0.381)
			(layers "F.Cu" "F.Mask" "F.Paste")
			(net "P1V8_CPU0_RT_1D")
		)
		(pad "2" smd rect
			(at 0.2667 0 270)
			(size 0.3048 0.381)
			(layers "F.Cu" "F.Mask" "F.Paste")
			(net "JTAG_TDI_RT_CPU0_P1")
		)
	)
	(footprint ""
		(layer "F.Cu")
		(at 154.17419 -102.688898)
		(property "Reference" "U239"
			(at -2.004314 1.730248 0)
			(unlocked yes)
			(layer "F.SilkS")
			(effects
				(font
					(size 0.7874 0.5842)
					(thickness 0.1524)
				)
				(justify left)
			)
		)
		(property "Value" ""
			(at 0 0 0)
			(layer "F.Fab")
			(effects
				(font
					(size 1.27 1.27)
				)
			)
		)
		(duplicate_pad_numbers_are_jumpers no)
		(fp_line
			(start -1.400048 1.100074)
			(end -1.400048 -1.100074)
			(stroke
				(width 0.1524)
				(type default)
			)
			(layer "F.SilkS")
		)
		(fp_line
			(start 1.400048 -1.100074)
			(end -1.400048 -1.100074)
			(stroke
				(width 0.1524)
				(type default)
			)
			(layer "F.SilkS")
		)
		(fp_line
			(start 1.400048 -1.100074)
			(end 1.400048 1.100074)
			(stroke
				(width 0.1524)
				(type default)
			)
			(layer "F.SilkS")
		)
		(fp_line
			(start 1.400048 1.100074)
			(end -1.400048 1.100074)
			(stroke
				(width 0.1524)
				(type default)
			)
			(layer "F.SilkS")
		)
		(fp_poly
			(pts
				(xy -2.606548 -0.418846) (xy -2.606548 -1.434846) (xy -1.590548 -0.926846)
			)
			(stroke
				(width 0)
				(type default)
			)
			(fill yes)
			(layer "F.SilkS")
		)
		(fp_line
			(start -0.674878 -1.100074)
			(end 0.674878 -1.100074)
			(stroke
				(width 0.1)
				(type default)
			)
			(layer "F.Fab")
		)
		(fp_line
			(start -0.674878 1.100074)
			(end -0.674878 -1.100074)
			(stroke
				(width 0.1)
				(type default)
			)
			(layer "F.Fab")
		)
		(fp_line
			(start 0.674878 -1.100074)
			(end 0.674878 1.100074)
			(stroke
				(width 0.1)
				(type default)
			)
			(layer "F.Fab")
		)
		(fp_line
			(start 0.674878 1.100074)
			(end -0.674878 1.100074)
			(stroke
				(width 0.1)
				(type default)
			)
			(layer "F.Fab")
		)
		(fp_poly
			(pts
				(xy -1.590548 -0.649986) (xy -2.606548 -1.157986) (xy -2.606548 -0.141986)
			)
			(stroke
				(width 0)
				(type default)
			)
			(fill yes)
			(layer "F.Fab")
		)
		(pad "1" smd rect
			(at -0.94996 -0.649986 270)
			(size 0.4318 0.6096)
			(layers "F.Cu" "F.Mask" "F.Paste")
			(net "PU_BUFFER_HDD_ACTIVITY")
		)
		(pad "2" smd rect
			(at -0.94996 0 270)
			(size 0.4318 0.6096)
			(layers "F.Cu" "F.Mask" "F.Paste")
			(net "LED_HDD_ACTIVITY_N")
		)
		(pad "3" smd rect
			(at -0.94996 0.649986 270)
			(size 0.4318 0.6096)
			(layers "F.Cu" "F.Mask" "F.Paste")
			(net "GND")
		)
		(pad "4" smd rect
			(at 0.94996 0.649986 270)
			(size 0.4318 0.6096)
			(layers "F.Cu" "F.Mask" "F.Paste")
			(net "LED_HDD_ACTIVITY_B_N")
		)
		(pad "5" smd rect
			(at 0.94996 -0.649986 270)
			(size 0.4318 0.6096)
			(layers "F.Cu" "F.Mask" "F.Paste")
			(net "P3V3_AUX")
		)
	)
	(footprint ""
		(layer "F.Cu")
		(at 87.24011 -325.661274)
		(property "Reference" "PL40"
			(at -3.16611 -16.704056 0)
			(unlocked yes)
			(layer "F.SilkS")
			(effects
				(font
					(size 0.7874 0.5842)
					(thickness 0.1524)
				)
				(justify left)
			)
		)
		(property "Value" ""
			(at 0 0 0)
			(layer "F.Fab")
			(effects
				(font
					(size 1.27 1.27)
				)
			)
		)
		(duplicate_pad_numbers_are_jumpers no)
		(fp_line
			(start -3.750056 -5.500116)
			(end -2.393442 -5.500116)
			(stroke
				(width 0.1524)
				(type default)
			)
			(layer "F.SilkS")
		)
		(fp_line
			(start -3.750056 5.500116)
			(end -3.750056 -5.500116)
			(stroke
				(width 0.1524)
				(type default)
			)
			(layer "F.SilkS")
		)
		(fp_line
			(start -2.393442 5.500116)
			(end -3.750056 5.500116)
			(stroke
				(width 0.1524)
				(type default)
			)
			(layer "F.SilkS")
		)
		(fp_line
			(start 2.393442 5.500116)
			(end 3.750056 5.500116)
			(stroke
				(width 0.1524)
				(type default)
			)
			(layer "F.SilkS")
		)
		(fp_line
			(start 3.750056 -5.500116)
			(end 2.393442 -5.500116)
			(stroke
				(width 0.1524)
				(type default)
			)
			(layer "F.SilkS")
		)
		(fp_line
			(start 3.750056 5.500116)
			(end 3.750056 -5.500116)
			(stroke
				(width 0.1524)
				(type default)
			)
			(layer "F.SilkS")
		)
		(fp_poly
			(pts
				(xy -3.9116 -4.249928) (xy -4.3434 -4.034028) (xy -4.3434 -4.465828)
			)
			(stroke
				(width 0)
				(type default)
			)
			(fill yes)
			(layer "F.SilkS")
		)
		(fp_line
			(start -3.750056 -5.500116)
			(end -3.750056 5.500116)
			(stroke
				(width 0.1)
				(type default)
			)
			(layer "F.Fab")
		)
		(fp_line
			(start -3.750056 5.500116)
			(end 3.750056 5.500116)
			(stroke
				(width 0.1)
				(type default)
			)
			(layer "F.Fab")
		)
		(fp_line
			(start 3.750056 -5.500116)
			(end -3.750056 -5.500116)
			(stroke
				(width 0.1)
				(type default)
			)
			(layer "F.Fab")
		)
		(fp_line
			(start 3.750056 5.500116)
			(end 3.750056 -5.500116)
			(stroke
				(width 0.1)
				(type default)
			)
			(layer "F.Fab")
		)
		(fp_poly
			(pts
				(xy -4.9276 -4.757928) (xy -4.9276 -3.741928) (xy -3.9116 -4.249928)
			)
			(stroke
				(width 0)
				(type default)
			)
			(fill yes)
			(layer "F.Fab")
		)
		(pad "1" smd rect
			(at 0 -4.249928 270)
			(size 2.413 4.5212)
			(layers "F.Cu" "F.Mask" "F.Paste")
			(net "SW_PVDDCR_CPU1_P1_SW1")
		)
		(pad "2" smd rect
			(at 0 -1.175004 270)
			(size 1.3716 4.5212)
			(layers "F.Cu" "F.Mask" "F.Paste")
			(net "IND_CPU1_P1_CPL5")
		)
		(pad "3" smd rect
			(at 0 1.175004 270)
			(size 1.3716 4.5212)
			(layers "F.Cu" "F.Mask" "F.Paste")
			(net "IND_CPU1_P1_CPL1")
		)
		(pad "4" smd rect
			(at 0 4.249928 270)
			(size 2.413 4.5212)
			(layers "F.Cu" "F.Mask" "F.Paste")
			(net "PVDDCR_CPU1_P1")
		)
	)
	(footprint ""
		(layer "F.Cu")
		(at 26.793444 -424.525694 180)
		(property "Reference" "R3274"
			(at 0 0 180)
			(layer "F.SilkS")
			(hide yes)
			(effects
				(font
					(size 1.27 1.27)
				)
			)
		)
		(property "Value" ""
			(at 0 0 180)
			(layer "F.Fab")
			(effects
				(font
					(size 1.27 1.27)
				)
			)
		)
		(duplicate_pad_numbers_are_jumpers no)
		(fp_line
			(start 0.7874 0.4064)
			(end -0.7874 0.4064)
			(stroke
				(width 0.1524)
				(type default)
			)
			(layer "F.SilkS")
		)
		(fp_line
			(start 0.7874 -0.4064)
			(end 0.7874 0.4064)
			(stroke
				(width 0.1524)
				(type default)
			)
			(layer "F.SilkS")
		)
		(fp_line
			(start -0.7874 0.4064)
			(end -0.7874 -0.4064)
			(stroke
				(width 0.1524)
				(type default)
			)
			(layer "F.SilkS")
		)
		(fp_line
			(start -0.7874 -0.4064)
			(end 0.7874 -0.4064)
			(stroke
				(width 0.1524)
				(type default)
			)
			(layer "F.SilkS")
		)
		(fp_line
			(start 0.67945 0.3048)
			(end 0.120396 0.3048)
			(stroke
				(width 0.1)
				(type default)
			)
			(layer "F.Fab")
		)
		(fp_line
			(start 0.67945 -0.3048)
			(end 0.67945 0.3048)
			(stroke
				(width 0.1)
				(type default)
			)
			(layer "F.Fab")
		)
		(fp_line
			(start 0.12065 -0.2794)
			(end 0.12065 -0.3048)
			(stroke
				(width 0.1)
				(type default)
			)
			(layer "F.Fab")
		)
		(fp_line
			(start 0.12065 -0.3048)
			(end 0.67945 -0.3048)
			(stroke
				(width 0.1)
				(type default)
			)
			(layer "F.Fab")
		)
		(fp_line
			(start 0.120396 0.3048)
			(end 0.120396 0.2794)
			(stroke
				(width 0.1)
				(type default)
			)
			(layer "F.Fab")
		)
		(fp_line
			(start 0.120396 0.2794)
			(end -0.12065 0.2794)
			(stroke
				(width 0.1)
				(type default)
			)
			(layer "F.Fab")
		)
		(fp_line
			(start -0.12065 0.3048)
			(end -0.67945 0.3048)
			(stroke
				(width 0.1)
				(type default)
			)
			(layer "F.Fab")
		)
		(fp_line
			(start -0.12065 0.2794)
			(end -0.12065 0.3048)
			(stroke
				(width 0.1)
				(type default)
			)
			(layer "F.Fab")
		)
		(fp_line
			(start -0.12065 -0.2794)
			(end 0.12065 -0.2794)
			(stroke
				(width 0.1)
				(type default)
			)
			(layer "F.Fab")
		)
		(fp_line
			(start -0.12065 -0.305054)
			(end -0.12065 -0.2794)
			(stroke
				(width 0.1)
				(type default)
			)
			(layer "F.Fab")
		)
		(fp_line
			(start -0.67945 0.3048)
			(end -0.67945 -0.305054)
			(stroke
				(width 0.1)
				(type default)
			)
			(layer "F.Fab")
		)
		(fp_line
			(start -0.67945 -0.305054)
			(end -0.12065 -0.305054)
			(stroke
				(width 0.1)
				(type default)
			)
			(layer "F.Fab")
		)
		(pad "1" smd circle
			(at -0.40005 0 180)
			(size 0 0)
			(layers "F.Cu" "F.Mask" "F.Paste")
			(net "FM_P2E_EQA0")
		)
		(pad "2" smd circle
			(at 0.40005 0 180)
			(size 0 0)
			(layers "F.Cu" "F.Mask" "F.Paste")
			(net "GND")
		)
	)
	(footprint ""
		(layer "F.Cu")
		(at 141.624812 -50.556414)
		(property "Reference" "C6027"
			(at 0 0 0)
			(layer "F.SilkS")
			(hide yes)
			(effects
				(font
					(size 1.27 1.27)
				)
			)
		)
		(property "Value" ""
			(at 0 0 0)
			(layer "F.Fab")
			(effects
				(font
					(size 1.27 1.27)
				)
			)
		)
		(duplicate_pad_numbers_are_jumpers no)
		(fp_line
			(start -1.524 -0.762)
			(end 1.524 -0.762)
			(stroke
				(width 0.1524)
				(type default)
			)
			(layer "F.SilkS")
		)
		(fp_line
			(start -1.524 0.762)
			(end -1.524 -0.762)
			(stroke
				(width 0.1524)
				(type default)
			)
			(layer "F.SilkS")
		)
		(fp_line
			(start 1.524 -0.762)
			(end 1.524 0.762)
			(stroke
				(width 0.1524)
				(type default)
			)
			(layer "F.SilkS")
		)
		(fp_line
			(start 1.524 0.762)
			(end -1.524 0.762)
			(stroke
				(width 0.1524)
				(type default)
			)
			(layer "F.SilkS")
		)
		(fp_line
			(start -1.1049 -0.724916)
			(end -1.1049 0.724916)
			(stroke
				(width 0.1)
				(type default)
			)
			(layer "F.Fab")
		)
		(fp_line
			(start -1.1049 0.724916)
			(end 1.1049 0.724916)
			(stroke
				(width 0.1)
				(type default)
			)
			(layer "F.Fab")
		)
		(fp_line
			(start 1.1049 -0.724916)
			(end -1.1049 -0.724916)
			(stroke
				(width 0.1)
				(type default)
			)
			(layer "F.Fab")
		)
		(fp_line
			(start 1.1049 0.724916)
			(end 1.1049 -0.724916)
			(stroke
				(width 0.1)
				(type default)
			)
			(layer "F.Fab")
		)
		(pad "1" smd rect
			(at -0.889 0 180)
			(size 1.016 1.27)
			(layers "F.Cu" "F.Mask" "F.Paste")
			(net "P5V_AUX")
		)
		(pad "2" smd rect
			(at 0.889 0 180)
			(size 1.016 1.27)
			(layers "F.Cu" "F.Mask" "F.Paste")
			(net "GND")
		)
	)
)
